# BASEBOARD_FAB2 (Tioga Pass) — schematic netlist excerpt (pin names and nets, part order shuffled) for the footprints in the layout excerpt that follows; sources: Cadence DE-HDL packaged netlist, KiCad conversion of Wiwynn_Tioga_Pass_MB.brd

R25W148  RES  4.75K 1% CHIP  pkg 0402  page 150 : A = GND ; B = RMII_BMC_OCP_TXD1_R
C5D11  CAP  10UF 4V 20% X6S  pkg 0603LF  page 42 : A = PVSA_CPU0 ; B = GND

EU4G2  MIC5166  IC  pkg DFN  page 229
  VREF  = VR_PVTT_GHJ_VREF
  BIAS  = VR_PVTT_GHJ_BIAS
  AGND  = GND
  VDDQ  = VSENSE_PVDDQ_GHJ_VTT
  PG  = PWRGD_PVTT_GHJ_CPU1_R
  SNS  = VR_PVTT_GHJ_SNS
  EN  = FM_PVTT_GHJ_EN_R
  PGND  = GND
  VTT  = PVTT_GHJ
  VIN  = PVDDQ_GHJ
  THPAD  = GND

(kicad_pcb
	(version 20260206)
	(generator "pcbnew")
	(generator_version "10.0")
	(general
		(thickness 1.6)
		(legacy_teardrops no)
	)
	(paper "A4")
	(title_block
		(title "Wiwynn_Tioga_Pass_MB.brd")
		(comment 1 "Tioga Pass / footprints 52-54 of 4770")
	)
	(layers
		(0 "F.Cu" signal "TOP")
		(4 "In1.Cu" signal "L2GND")
		(6 "In2.Cu" signal "L3")
		(8 "In3.Cu" signal "L4GND")
		(10 "In4.Cu" signal "L5")
		(12 "In5.Cu" signal "L6GND")
		(14 "In6.Cu" signal "L7VCC")
		(16 "In7.Cu" signal "L8VCC")
		(18 "In8.Cu" signal "L9GND")
		(20 "In9.Cu" signal "L10")
		(22 "In10.Cu" signal "L11GND")
		(24 "In11.Cu" signal "L12")
		(26 "In12.Cu" signal "L13GND")
		(2 "B.Cu" signal "BOTTOM")
		(9 "F.Adhes" user "F.Adhesive")
		(11 "B.Adhes" user "B.Adhesive")
		(13 "F.Paste" user "Package Geometry/Pastemask Top")
		(15 "B.Paste" user "Package Geometry/Pastemask Bottom")
		(5 "F.SilkS" user "Ref Des/Silkscreen Top")
		(7 "B.SilkS" user "Ref Des/Silkscreen Bottom")
		(1 "F.Mask" user "Board Geometry/Soldermask Top")
		(3 "B.Mask" user "Board Geometry/Soldermask Bottom")
		(17 "Dwgs.User" user "User.Drawings")
		(19 "Cmts.User" user "User.Comments")
		(21 "Eco1.User" user "User.Eco1")
		(23 "Eco2.User" user "User.Eco2")
		(25 "Edge.Cuts" user "Board Geometry/Outline")
		(27 "Margin" user)
		(31 "F.CrtYd" user "Package Geometry/Place Bound Top")
		(29 "B.CrtYd" user "Package Geometry/Place Bound Bottom")
		(35 "F.Fab" user "Ref Des/Assembly Top")
		(33 "B.Fab" user "Ref Des/Assembly Bottom")
	)
	(footprint ""
		(layer "F.Cu")
		(at 171.8818 -3.175 180)
		(property "Reference" "EU4G2"
			(at 2.9718 -1.42367 0)
			(unlocked yes)
			(layer "F.SilkS")
			(effects
				(font
					(size 0.7874 0.5842)
					(thickness 0.1524)
				)
				(justify left)
			)
		)
		(property "Value" ""
			(at 0 0 180)
			(layer "F.Fab")
			(effects
				(font
					(size 1.27 1.27)
				)
			)
		)
		(duplicate_pad_numbers_are_jumpers no)
		(fp_circle
			(center -0.835152 -0.417322)
			(end -0.962152 -0.417322)
			(stroke
				(width 0.254)
				(type default)
			)
			(fill no)
			(layer "F.SilkS")
		)
		(fp_poly
			(pts
				(xy -0.064516 -1.0922) (xy -0.064516 -0.3302) (xy 0.697484 -1.0922)
			)
			(stroke
				(width 0)
				(type default)
			)
			(fill yes)
			(layer "F.SilkS")
		)
		(fp_rect
			(start 0.597408 2.295398)
			(end 2.273808 -0.295402)
			(stroke
				(width 0)
				(type default)
			)
			(fill yes)
			(layer "F.Paste")
		)
		(fp_rect
			(start -0.064516 2.500122)
			(end 2.935478 -0.500126)
			(stroke
				(width 0)
				(type default)
			)
			(fill no)
			(layer "F.CrtYd")
		)
		(fp_line
			(start 2.935478 2.500122)
			(end -0.064516 2.500122)
			(stroke
				(width 0.1)
				(type default)
			)
			(layer "F.Fab")
		)
		(fp_line
			(start 2.935478 -0.500126)
			(end 2.935478 2.500122)
			(stroke
				(width 0.1)
				(type default)
			)
			(layer "F.Fab")
		)
		(fp_line
			(start -0.064516 2.500122)
			(end -0.064516 -0.500126)
			(stroke
				(width 0.1)
				(type default)
			)
			(layer "F.Fab")
		)
		(fp_line
			(start -0.064516 -0.500126)
			(end 2.935478 -0.500126)
			(stroke
				(width 0.1)
				(type default)
			)
			(layer "F.Fab")
		)
		(fp_circle
			(center -0.835152 -0.417322)
			(end -0.962152 -0.417322)
			(stroke
				(width 0.254)
				(type default)
			)
			(fill no)
			(layer "F.Fab")
		)
		(pad "1" smd rect
			(at 0 0 180)
			(size 0.6858 0.3048)
			(layers "F.Cu" "F.Mask" "F.Paste")
			(net "VR_PVTT_GHJ_VREF")
		)
		(pad "2" smd rect
			(at 0 0.500126 180)
			(size 0.6858 0.3048)
			(layers "F.Cu" "F.Mask" "F.Paste")
			(net "VR_PVTT_GHJ_BIAS")
		)
		(pad "3" smd rect
			(at 0 0.999998 180)
			(size 0.6858 0.3048)
			(layers "F.Cu" "F.Mask" "F.Paste")
			(net "GND")
		)
		(pad "4" smd rect
			(at 0 1.500124 180)
			(size 0.6858 0.3048)
			(layers "F.Cu" "F.Mask" "F.Paste")
			(net "VSENSE_PVDDQ_GHJ_VTT")
		)
		(pad "5" smd rect
			(at 0 1.999996 180)
			(size 0.6858 0.3048)
			(layers "F.Cu" "F.Mask" "F.Paste")
			(net "PWRGD_PVTT_GHJ_CPU1_R")
		)
		(pad "6" smd rect
			(at 2.871216 1.999996 180)
			(size 0.6858 0.3048)
			(layers "F.Cu" "F.Mask" "F.Paste")
			(net "VR_PVTT_GHJ_SNS")
		)
		(pad "7" smd rect
			(at 2.871216 1.500124 180)
			(size 0.6858 0.3048)
			(layers "F.Cu" "F.Mask" "F.Paste")
			(net "FM_PVTT_GHJ_EN_R")
		)
		(pad "8" smd rect
			(at 2.871216 0.999998 180)
			(size 0.6858 0.3048)
			(layers "F.Cu" "F.Mask" "F.Paste")
			(net "GND")
		)
		(pad "9" smd rect
			(at 2.871216 0.500126 180)
			(size 0.6858 0.3048)
			(layers "F.Cu" "F.Mask" "F.Paste")
			(net "PVTT_GHJ")
		)
		(pad "10" smd rect
			(at 2.871216 0 180)
			(size 0.6858 0.3048)
			(layers "F.Cu" "F.Mask" "F.Paste")
			(net "PVDDQ_GHJ")
		)
		(pad "11" smd rect
			(at 1.435608 0.999998 180)
			(size 1.6764 2.5908)
			(layers "F.Cu" "F.Mask" "F.Paste")
			(net "GND")
		)
	)
	(footprint ""
		(layer "F.Cu")
		(at 401.55368 -28.49499 180)
		(property "Reference" "R25W148"
			(at -0.8382 -0.67818 180)
			(unlocked yes)
			(layer "F.SilkS")
			(effects
				(font
					(size 0.4064 0.254)
					(thickness 0.1524)
				)
				(justify left)
			)
		)
		(property "Value" ""
			(at 0 0 180)
			(layer "F.Fab")
			(effects
				(font
					(size 1.27 1.27)
				)
			)
		)
		(duplicate_pad_numbers_are_jumpers no)
		(fp_poly
			(pts
				(xy -0.2794 -0.1016) (xy 0.2794 -0.1016) (xy 0.2794 0.9906) (xy -0.2794 0.9906)
			)
			(stroke
				(width 0)
				(type default)
			)
			(fill no)
			(layer "F.CrtYd")
		)
		(fp_line
			(start 0.2794 0.9906)
			(end 0.2794 -0.1016)
			(stroke
				(width 0.1)
				(type default)
			)
			(layer "F.Fab")
		)
		(fp_line
			(start 0.2794 -0.1016)
			(end -0.2794 -0.1016)
			(stroke
				(width 0.1)
				(type default)
			)
			(layer "F.Fab")
		)
		(fp_line
			(start -0.2794 0.9906)
			(end 0.2794 0.9906)
			(stroke
				(width 0.1)
				(type default)
			)
			(layer "F.Fab")
		)
		(fp_line
			(start -0.2794 -0.1016)
			(end -0.2794 0.9906)
			(stroke
				(width 0.1)
				(type default)
			)
			(layer "F.Fab")
		)
		(pad "1" smd rect
			(at 0 0 180)
			(size 0.508 0.508)
			(layers "F.Cu" "F.Mask" "F.Paste")
			(net "GND")
		)
		(pad "2" smd rect
			(at 0 0.889 180)
			(size 0.508 0.508)
			(layers "F.Cu" "F.Mask" "F.Paste")
			(net "RMII_BMC_OCP_TXD1_R")
		)
		(zone
			(layer "F.Cu")
			(hatch none 0.5)
			(connect_pads
				(clearance 0)
			)
			(min_thickness 0.25)
			(keepout
				(tracks not_allowed)
				(vias allowed)
				(pads allowed)
				(copperpour not_allowed)
				(footprints allowed)
			)
			(placement
				(enabled no)
				(sheetname "")
			)
			(fill
				(thermal_gap 0.5)
				(thermal_bridge_width 0.5)
				(island_removal_mode 0)
			)
			(polygon
				(pts
					(xy 401.80768 -29.12999) (xy 401.29968 -29.12999) (xy 401.29968 -28.74899) (xy 401.80768 -28.74899)
				)
			)
		)
		(zone
			(layer "F.Cu")
			(hatch none 0.5)
			(connect_pads
				(clearance 0)
			)
			(min_thickness 0.25)
			(keepout
				(tracks allowed)
				(vias not_allowed)
				(pads allowed)
				(copperpour not_allowed)
				(footprints allowed)
			)
			(placement
				(enabled no)
				(sheetname "")
			)
			(fill
				(thermal_gap 0.5)
				(thermal_bridge_width 0.5)
				(island_removal_mode 0)
			)
			(polygon
				(pts
					(xy 401.80768 -28.74899) (xy 401.29968 -28.74899) (xy 401.29968 -29.12999) (xy 401.80768 -29.12999)
				)
			)
		)
	)
	(footprint ""
		(layer "F.Cu")
		(at 259.452872 -81.573116)
		(property "Reference" "C5D11"
			(at 0 0 0)
			(layer "F.SilkS")
			(hide yes)
			(effects
				(font
					(size 1.27 1.27)
				)
			)
		)
		(property "Value" ""
			(at 0 0 0)
			(layer "F.Fab")
			(effects
				(font
					(size 1.27 1.27)
				)
			)
		)
		(duplicate_pad_numbers_are_jumpers no)
		(fp_poly
			(pts
				(xy -0.4953 -0.2032) (xy 0.4953 -0.2032) (xy 0.4953 1.6002) (xy -0.4953 1.6002)
			)
			(stroke
				(width 0)
				(type default)
			)
			(fill no)
			(layer "F.CrtYd")
		)
		(fp_line
			(start -0.4953 -0.2032)
			(end 0.4953 -0.2032)
			(stroke
				(width 0.1)
				(type default)
			)
			(layer "F.Fab")
		)
		(fp_line
			(start -0.4953 1.6002)
			(end -0.4953 -0.2032)
			(stroke
				(width 0.1)
				(type default)
			)
			(layer "F.Fab")
		)
		(fp_line
			(start 0.4953 -0.2032)
			(end 0.4953 1.6002)
			(stroke
				(width 0.1)
				(type default)
			)
			(layer "F.Fab")
		)
		(fp_line
			(start 0.4953 1.6002)
			(end -0.4953 1.6002)
			(stroke
				(width 0.1)
				(type default)
			)
			(layer "F.Fab")
		)
		(pad "1" smd rect
			(at 0 0)
			(size 0.762 0.889)
			(layers "F.Cu" "F.Mask" "F.Paste")
			(net "PVSA_CPU0")
		)
		(pad "2" smd rect
			(at 0 1.397)
			(size 0.762 0.889)
			(layers "F.Cu" "F.Mask" "F.Paste")
			(net "GND")
		)
		(zone
			(layer "F.Cu")
			(hatch none 0.5)
			(connect_pads
				(clearance 0)
			)
			(min_thickness 0.25)
			(keepout
				(tracks not_allowed)
				(vias allowed)
				(pads allowed)
				(copperpour not_allowed)
				(footprints allowed)
			)
			(placement
				(enabled no)
				(sheetname "")
			)
			(fill
				(thermal_gap 0.5)
				(thermal_bridge_width 0.5)
				(island_removal_mode 0)
			)
			(polygon
				(pts
					(xy 259.071872 -81.128616) (xy 259.833872 -81.128616) (xy 259.833872 -80.620616) (xy 259.071872 -80.620616)
				)
			)
		)
	)
)
